(kicad_pcb
	(version 20260206)
	(generator "pcbnew")
	(generator_version "10.0")
	(general
		(thickness 1.6)
		(legacy_teardrops no)
	)
	(paper "A4")
	(title_block
		(title "Wiwynn_Tioga_Pass_MB.brd")
		(comment 1 "Tioga Pass / footprints 1219-1225 of 4770")
	)
	(layers
		(0 "F.Cu" signal "TOP")
		(4 "In1.Cu" signal "L2GND")
		(6 "In2.Cu" signal "L3")
		(8 "In3.Cu" signal "L4GND")
		(10 "In4.Cu" signal "L5")
		(12 "In5.Cu" signal "L6GND")
		(14 "In6.Cu" signal "L7VCC")
		(16 "In7.Cu" signal "L8VCC")
		(18 "In8.Cu" signal "L9GND")
		(20 "In9.Cu" signal "L10")
		(22 "In10.Cu" signal "L11GND")
		(24 "In11.Cu" signal "L12")
		(26 "In12.Cu" signal "L13GND")
		(2 "B.Cu" signal "BOTTOM")
		(9 "F.Adhes" user "F.Adhesive")
		(11 "B.Adhes" user "B.Adhesive")
		(13 "F.Paste" user "Package Geometry/Pastemask Top")
		(15 "B.Paste" user "Package Geometry/Pastemask Bottom")
		(5 "F.SilkS" user "Ref Des/Silkscreen Top")
		(7 "B.SilkS" user "Ref Des/Silkscreen Bottom")
		(1 "F.Mask" user "Board Geometry/Soldermask Top")
		(3 "B.Mask" user "Board Geometry/Soldermask Bottom")
		(17 "Dwgs.User" user "User.Drawings")
		(19 "Cmts.User" user "User.Comments")
		(21 "Eco1.User" user "User.Eco1")
		(23 "Eco2.User" user "User.Eco2")
		(25 "Edge.Cuts" user "Board Geometry/Outline")
		(27 "Margin" user)
		(31 "F.CrtYd" user "Package Geometry/Place Bound Top")
		(29 "B.CrtYd" user "Package Geometry/Place Bound Bottom")
		(35 "F.Fab" user "Ref Des/Assembly Top")
		(33 "B.Fab" user "Ref Des/Assembly Bottom")
	)
	(footprint ""
		(layer "F.Cu")
		(at 337.404202 -121.282968 90)
		(property "Reference" "C6B15"
			(at -0.8382 -0.67818 90)
			(unlocked yes)
			(layer "F.SilkS")
			(effects
				(font
					(size 0.4064 0.254)
					(thickness 0.1524)
				)
				(justify left)
			)
		)
		(property "Value" ""
			(at 0 0 90)
			(layer "F.Fab")
			(effects
				(font
					(size 1.27 1.27)
				)
			)
		)
		(duplicate_pad_numbers_are_jumpers no)
		(fp_poly
			(pts
				(xy 0.3048 -0.1016) (xy 0.3048 0.9906) (xy -0.3048 0.9906) (xy -0.3048 -0.1016)
			)
			(stroke
				(width 0)
				(type default)
			)
			(fill no)
			(layer "F.CrtYd")
		)
		(fp_line
			(start 0.3048 -0.1016)
			(end -0.3048 -0.1016)
			(stroke
				(width 0.1)
				(type default)
			)
			(layer "F.Fab")
		)
		(fp_line
			(start -0.3048 -0.1016)
			(end -0.3048 0.9906)
			(stroke
				(width 0.1)
				(type default)
			)
			(layer "F.Fab")
		)
		(fp_line
			(start 0.3048 0.9906)
			(end 0.3048 -0.1016)
			(stroke
				(width 0.1)
				(type default)
			)
			(layer "F.Fab")
		)
		(fp_line
			(start -0.3048 0.9906)
			(end 0.3048 0.9906)
			(stroke
				(width 0.1)
				(type default)
			)
			(layer "F.Fab")
		)
		(pad "1" smd rect
			(at 0 0 90)
			(size 0.508 0.508)
			(layers "F.Cu" "F.Mask" "F.Paste")
			(net "P3E_CPU0_PE1_PCH_TXN<10>")
		)
		(pad "2" smd rect
			(at 0 0.889 90)
			(size 0.508 0.508)
			(layers "F.Cu" "F.Mask" "F.Paste")
			(net "P3E_CPU0_PE1_PCH_C_TXN<10>")
		)
		(zone
			(layer "F.Cu")
			(hatch none 0.5)
			(connect_pads
				(clearance 0)
			)
			(min_thickness 0.25)
			(keepout
				(tracks allowed)
				(vias not_allowed)
				(pads allowed)
				(copperpour not_allowed)
				(footprints allowed)
			)
			(placement
				(enabled no)
				(sheetname "")
			)
			(fill
				(thermal_gap 0.5)
				(thermal_bridge_width 0.5)
				(island_removal_mode 0)
			)
			(polygon
				(pts
					(xy 337.658202 -121.028968) (xy 337.658202 -121.536968) (xy 338.039202 -121.536968) (xy 338.039202 -121.028968)
				)
			)
		)
		(zone
			(layer "F.Cu")
			(hatch none 0.5)
			(connect_pads
				(clearance 0)
			)
			(min_thickness 0.25)
			(keepout
				(tracks not_allowed)
				(vias allowed)
				(pads allowed)
				(copperpour not_allowed)
				(footprints allowed)
			)
			(placement
				(enabled no)
				(sheetname "")
			)
			(fill
				(thermal_gap 0.5)
				(thermal_bridge_width 0.5)
				(island_removal_mode 0)
			)
			(polygon
				(pts
					(xy 338.039202 -121.028968) (xy 338.039202 -121.536968) (xy 337.658202 -121.536968) (xy 337.658202 -121.028968)
				)
			)
		)
	)
	(footprint ""
		(layer "F.Cu")
		(at 179.705 -64.135 180)
		(property "Reference" "R4E3"
			(at 0 0 180)
			(layer "F.SilkS")
			(hide yes)
			(effects
				(font
					(size 1.27 1.27)
				)
			)
		)
		(property "Value" ""
			(at 0 0 180)
			(layer "F.Fab")
			(effects
				(font
					(size 1.27 1.27)
				)
			)
		)
		(duplicate_pad_numbers_are_jumpers no)
		(fp_rect
			(start 0.2794 -0.1016)
			(end -0.2794 0.9906)
			(stroke
				(width 0)
				(type default)
			)
			(fill no)
			(layer "F.CrtYd")
		)
		(fp_line
			(start 0.2794 0.9906)
			(end 0.2794 -0.1016)
			(stroke
				(width 0.1)
				(type default)
			)
			(layer "F.Fab")
		)
		(fp_line
			(start 0.2794 -0.1016)
			(end -0.2794 -0.1016)
			(stroke
				(width 0.1)
				(type default)
			)
			(layer "F.Fab")
		)
		(fp_line
			(start -0.2794 0.9906)
			(end 0.2794 0.9906)
			(stroke
				(width 0.1)
				(type default)
			)
			(layer "F.Fab")
		)
		(fp_line
			(start -0.2794 -0.1016)
			(end -0.2794 0.9906)
			(stroke
				(width 0.1)
				(type default)
			)
			(layer "F.Fab")
		)
		(pad "1" smd rect
			(at 0 0 180)
			(size 0.508 0.508)
			(layers "F.Cu" "F.Mask" "F.Paste")
			(net "P3V3_STBY")
		)
		(pad "2" smd rect
			(at 0 0.889 180)
			(size 0.508 0.508)
			(layers "F.Cu" "F.Mask" "F.Paste")
			(net "IRQ_PVCCIN_CPU0_VRHOT_LVC3_R_N")
		)
		(zone
			(layer "F.Cu")
			(hatch none 0.5)
			(connect_pads
				(clearance 0)
			)
			(min_thickness 0.25)
			(keepout
				(tracks allowed)
				(vias not_allowed)
				(pads allowed)
				(copperpour not_allowed)
				(footprints allowed)
			)
			(placement
				(enabled no)
				(sheetname "")
			)
			(fill
				(thermal_gap 0.5)
				(thermal_bridge_width 0.5)
				(island_removal_mode 0)
			)
			(polygon
				(pts
					(xy 179.451 -64.389) (xy 179.959 -64.389) (xy 179.959 -64.77) (xy 179.451 -64.77)
				)
			)
		)
		(zone
			(layer "F.Cu")
			(hatch none 0.5)
			(connect_pads
				(clearance 0)
			)
			(min_thickness 0.25)
			(keepout
				(tracks not_allowed)
				(vias allowed)
				(pads allowed)
				(copperpour not_allowed)
				(footprints allowed)
			)
			(placement
				(enabled no)
				(sheetname "")
			)
			(fill
				(thermal_gap 0.5)
				(thermal_bridge_width 0.5)
				(island_removal_mode 0)
			)
			(polygon
				(pts
					(xy 179.451 -64.389) (xy 179.959 -64.389) (xy 179.959 -64.77) (xy 179.451 -64.77)
				)
			)
		)
	)
	(footprint ""
		(layer "F.Cu")
		(at 442.364876 -14.123924 90)
		(property "Reference" "R2U40"
			(at 0 0 90)
			(layer "F.SilkS")
			(hide yes)
			(effects
				(font
					(size 1.27 1.27)
				)
			)
		)
		(property "Value" ""
			(at 0 0 90)
			(layer "F.Fab")
			(effects
				(font
					(size 1.27 1.27)
				)
			)
		)
		(duplicate_pad_numbers_are_jumpers no)
		(fp_poly
			(pts
				(xy -0.2794 -0.1016) (xy 0.2794 -0.1016) (xy 0.2794 0.9906) (xy -0.2794 0.9906)
			)
			(stroke
				(width 0)
				(type default)
			)
			(fill no)
			(layer "F.CrtYd")
		)
		(fp_line
			(start 0.2794 -0.1016)
			(end -0.2794 -0.1016)
			(stroke
				(width 0.1)
				(type default)
			)
			(layer "F.Fab")
		)
		(fp_line
			(start -0.2794 -0.1016)
			(end -0.2794 0.9906)
			(stroke
				(width 0.1)
				(type default)
			)
			(layer "F.Fab")
		)
		(fp_line
			(start 0.2794 0.9906)
			(end 0.2794 -0.1016)
			(stroke
				(width 0.1)
				(type default)
			)
			(layer "F.Fab")
		)
		(fp_line
			(start -0.2794 0.9906)
			(end 0.2794 0.9906)
			(stroke
				(width 0.1)
				(type default)
			)
			(layer "F.Fab")
		)
		(pad "1" smd rect
			(at 0 0 90)
			(size 0.508 0.508)
			(layers "F.Cu" "F.Mask" "F.Paste")
			(net "PVCCIO_CPU0")
		)
		(pad "2" smd rect
			(at 0 0.889 90)
			(size 0.508 0.508)
			(layers "F.Cu" "F.Mask" "F.Paste")
			(net "H_CPU0_MEMABC_MEMHOT_G_N")
		)
		(zone
			(layer "F.Cu")
			(hatch none 0.5)
			(connect_pads
				(clearance 0)
			)
			(min_thickness 0.25)
			(keepout
				(tracks allowed)
				(vias not_allowed)
				(pads allowed)
				(copperpour not_allowed)
				(footprints allowed)
			)
			(placement
				(enabled no)
				(sheetname "")
			)
			(fill
				(thermal_gap 0.5)
				(thermal_bridge_width 0.5)
				(island_removal_mode 0)
			)
			(polygon
				(pts
					(xy 442.618876 -13.869924) (xy 442.618876 -14.377924) (xy 442.999876 -14.377924) (xy 442.999876 -13.869924)
				)
			)
		)
		(zone
			(layer "F.Cu")
			(hatch none 0.5)
			(connect_pads
				(clearance 0)
			)
			(min_thickness 0.25)
			(keepout
				(tracks not_allowed)
				(vias allowed)
				(pads allowed)
				(copperpour not_allowed)
				(footprints allowed)
			)
			(placement
				(enabled no)
				(sheetname "")
			)
			(fill
				(thermal_gap 0.5)
				(thermal_bridge_width 0.5)
				(island_removal_mode 0)
			)
			(polygon
				(pts
					(xy 442.999876 -13.869924) (xy 442.999876 -14.377924) (xy 442.618876 -14.377924) (xy 442.618876 -13.869924)
				)
			)
		)
	)
	(footprint ""
		(layer "F.Cu")
		(at 49.4284 -63.080392)
		(property "Reference" "C1E3"
			(at 0 0 0)
			(layer "F.SilkS")
			(hide yes)
			(effects
				(font
					(size 1.27 1.27)
				)
			)
		)
		(property "Value" ""
			(at 0 0 0)
			(layer "F.Fab")
			(effects
				(font
					(size 1.27 1.27)
				)
			)
		)
		(duplicate_pad_numbers_are_jumpers no)
		(fp_poly
			(pts
				(xy -0.4953 -0.2032) (xy 0.4953 -0.2032) (xy 0.4953 1.6002) (xy -0.4953 1.6002)
			)
			(stroke
				(width 0)
				(type default)
			)
			(fill no)
			(layer "F.CrtYd")
		)
		(fp_line
			(start -0.4953 -0.2032)
			(end 0.4953 -0.2032)
			(stroke
				(width 0.1)
				(type default)
			)
			(layer "F.Fab")
		)
		(fp_line
			(start -0.4953 1.6002)
			(end -0.4953 -0.2032)
			(stroke
				(width 0.1)
				(type default)
			)
			(layer "F.Fab")
		)
		(fp_line
			(start 0.4953 -0.2032)
			(end 0.4953 1.6002)
			(stroke
				(width 0.1)
				(type default)
			)
			(layer "F.Fab")
		)
		(fp_line
			(start 0.4953 1.6002)
			(end -0.4953 1.6002)
			(stroke
				(width 0.1)
				(type default)
			)
			(layer "F.Fab")
		)
		(pad "1" smd rect
			(at 0 0)
			(size 0.762 0.889)
			(layers "F.Cu" "F.Mask" "F.Paste")
			(net "PVCCIN_CPU1")
		)
		(pad "2" smd rect
			(at 0 1.397)
			(size 0.762 0.889)
			(layers "F.Cu" "F.Mask" "F.Paste")
			(net "GND")
		)
		(zone
			(layer "F.Cu")
			(hatch none 0.5)
			(connect_pads
				(clearance 0)
			)
			(min_thickness 0.25)
			(keepout
				(tracks not_allowed)
				(vias allowed)
				(pads allowed)
				(copperpour not_allowed)
				(footprints allowed)
			)
			(placement
				(enabled no)
				(sheetname "")
			)
			(fill
				(thermal_gap 0.5)
				(thermal_bridge_width 0.5)
				(island_removal_mode 0)
			)
			(polygon
				(pts
					(xy 49.0474 -62.635892) (xy 49.8094 -62.635892) (xy 49.8094 -62.127892) (xy 49.0474 -62.127892)
				)
			)
		)
	)
	(footprint ""
		(layer "F.Cu")
		(at 181.339998 1.536192)
		(property "Reference" "C4G23"
			(at 0 0 0)
			(layer "F.SilkS")
			(hide yes)
			(effects
				(font
					(size 1.27 1.27)
				)
			)
		)
		(property "Value" ""
			(at 0 0 0)
			(layer "F.Fab")
			(effects
				(font
					(size 1.27 1.27)
				)
			)
		)
		(duplicate_pad_numbers_are_jumpers no)
		(fp_rect
			(start -0.3048 0.9906)
			(end 0.3048 -0.1016)
			(stroke
				(width 0)
				(type default)
			)
			(fill no)
			(layer "F.CrtYd")
		)
		(fp_line
			(start -0.3048 -0.1016)
			(end -0.3048 0.9906)
			(stroke
				(width 0.1)
				(type default)
			)
			(layer "F.Fab")
		)
		(fp_line
			(start -0.3048 0.9906)
			(end 0.3048 0.9906)
			(stroke
				(width 0.1)
				(type default)
			)
			(layer "F.Fab")
		)
		(fp_line
			(start 0.3048 -0.1016)
			(end -0.3048 -0.1016)
			(stroke
				(width 0.1)
				(type default)
			)
			(layer "F.Fab")
		)
		(fp_line
			(start 0.3048 0.9906)
			(end 0.3048 -0.1016)
			(stroke
				(width 0.1)
				(type default)
			)
			(layer "F.Fab")
		)
		(pad "1" smd rect
			(at 0 0)
			(size 0.508 0.508)
			(layers "F.Cu" "F.Mask" "F.Paste")
			(net "FM_PVTT_ABC_EN_R")
		)
		(pad "2" smd rect
			(at 0 0.889)
			(size 0.508 0.508)
			(layers "F.Cu" "F.Mask" "F.Paste")
			(net "GND")
		)
		(zone
			(layer "F.Cu")
			(hatch none 0.5)
			(connect_pads
				(clearance 0)
			)
			(min_thickness 0.25)
			(keepout
				(tracks allowed)
				(vias not_allowed)
				(pads allowed)
				(copperpour not_allowed)
				(footprints allowed)
			)
			(placement
				(enabled no)
				(sheetname "")
			)
			(fill
				(thermal_gap 0.5)
				(thermal_bridge_width 0.5)
				(island_removal_mode 0)
			)
			(polygon
				(pts
					(xy 181.085998 2.171192) (xy 181.593998 2.171192) (xy 181.593998 1.790192) (xy 181.085998 1.790192)
				)
			)
		)
		(zone
			(layer "F.Cu")
			(hatch none 0.5)
			(connect_pads
				(clearance 0)
			)
			(min_thickness 0.25)
			(keepout
				(tracks not_allowed)
				(vias allowed)
				(pads allowed)
				(copperpour not_allowed)
				(footprints allowed)
			)
			(placement
				(enabled no)
				(sheetname "")
			)
			(fill
				(thermal_gap 0.5)
				(thermal_bridge_width 0.5)
				(island_removal_mode 0)
			)
			(polygon
				(pts
					(xy 181.085998 2.171192) (xy 181.593998 2.171192) (xy 181.593998 1.790192) (xy 181.085998 1.790192)
				)
			)
		)
	)
	(footprint ""
		(layer "F.Cu")
		(at 411.0355 -109.855 -90)
		(property "Reference" "R8C7"
			(at 0 0 270)
			(layer "F.SilkS")
			(hide yes)
			(effects
				(font
					(size 1.27 1.27)
				)
			)
		)
		(property "Value" ""
			(at 0 0 270)
			(layer "F.Fab")
			(effects
				(font
					(size 1.27 1.27)
				)
			)
		)
		(duplicate_pad_numbers_are_jumpers no)
		(fp_poly
			(pts
				(xy -0.2794 -0.1016) (xy 0.2794 -0.1016) (xy 0.2794 0.9906) (xy -0.2794 0.9906)
			)
			(stroke
				(width 0)
				(type default)
			)
			(fill no)
			(layer "F.CrtYd")
		)
		(fp_line
			(start -0.2794 0.9906)
			(end 0.2794 0.9906)
			(stroke
				(width 0.1)
				(type default)
			)
			(layer "F.Fab")
		)
		(fp_line
			(start 0.2794 0.9906)
			(end 0.2794 -0.1016)
			(stroke
				(width 0.1)
				(type default)
			)
			(layer "F.Fab")
		)
		(fp_line
			(start -0.2794 -0.1016)
			(end -0.2794 0.9906)
			(stroke
				(width 0.1)
				(type default)
			)
			(layer "F.Fab")
		)
		(fp_line
			(start 0.2794 -0.1016)
			(end -0.2794 -0.1016)
			(stroke
				(width 0.1)
				(type default)
			)
			(layer "F.Fab")
		)
		(pad "1" smd rect
			(at 0 0 270)
			(size 0.508 0.508)
			(layers "F.Cu" "F.Mask" "F.Paste")
			(net "P3V3_STBY")
		)
		(pad "2" smd rect
			(at 0 0.889 270)
			(size 0.508 0.508)
			(layers "F.Cu" "F.Mask" "F.Paste")
			(net "FM_SLT_CFG0")
		)
		(zone
			(layer "F.Cu")
			(hatch none 0.5)
			(connect_pads
				(clearance 0)
			)
			(min_thickness 0.25)
			(keepout
				(tracks not_allowed)
				(vias allowed)
				(pads allowed)
				(copperpour not_allowed)
				(footprints allowed)
			)
			(placement
				(enabled no)
				(sheetname "")
			)
			(fill
				(thermal_gap 0.5)
				(thermal_bridge_width 0.5)
				(island_removal_mode 0)
			)
			(polygon
				(pts
					(xy 410.4005 -110.109) (xy 410.4005 -109.601) (xy 410.7815 -109.601) (xy 410.7815 -110.109)
				)
			)
		)
		(zone
			(layer "F.Cu")
			(hatch none 0.5)
			(connect_pads
				(clearance 0)
			)
			(min_thickness 0.25)
			(keepout
				(tracks allowed)
				(vias not_allowed)
				(pads allowed)
				(copperpour not_allowed)
				(footprints allowed)
			)
			(placement
				(enabled no)
				(sheetname "")
			)
			(fill
				(thermal_gap 0.5)
				(thermal_bridge_width 0.5)
				(island_removal_mode 0)
			)
			(polygon
				(pts
					(xy 410.7815 -110.109) (xy 410.7815 -109.601) (xy 410.4005 -109.601) (xy 410.4005 -110.109)
				)
			)
		)
	)
	(footprint ""
		(layer "F.Cu")
		(at 173.736 -64.63538 90)
		(property "Reference" "C4W2"
			(at -0.8382 -0.67818 90)
			(unlocked yes)
			(layer "F.SilkS")
			(effects
				(font
					(size 0.4064 0.254)
					(thickness 0.1524)
				)
				(justify left)
			)
		)
		(property "Value" ""
			(at 0 0 90)
			(layer "F.Fab")
			(effects
				(font
					(size 1.27 1.27)
				)
			)
		)
		(duplicate_pad_numbers_are_jumpers no)
		(fp_poly
			(pts
				(xy 0.3048 -0.1016) (xy 0.3048 0.9906) (xy -0.3048 0.9906) (xy -0.3048 -0.1016)
			)
			(stroke
				(width 0)
				(type default)
			)
			(fill no)
			(layer "F.CrtYd")
		)
		(fp_line
			(start 0.3048 -0.1016)
			(end -0.3048 -0.1016)
			(stroke
				(width 0.1)
				(type default)
			)
			(layer "F.Fab")
		)
		(fp_line
			(start -0.3048 -0.1016)
			(end -0.3048 0.9906)
			(stroke
				(width 0.1)
				(type default)
			)
			(layer "F.Fab")
		)
		(fp_line
			(start 0.3048 0.9906)
			(end 0.3048 -0.1016)
			(stroke
				(width 0.1)
				(type default)
			)
			(layer "F.Fab")
		)
		(fp_line
			(start -0.3048 0.9906)
			(end 0.3048 0.9906)
			(stroke
				(width 0.1)
				(type default)
			)
			(layer "F.Fab")
		)
		(pad "1" smd rect
			(at 0 0 90)
			(size 0.508 0.508)
			(layers "F.Cu" "F.Mask" "F.Paste")
			(net "A_TSENSE_PVCCIO_CPU1")
		)
		(pad "2" smd rect
			(at 0 0.889 90)
			(size 0.508 0.508)
			(layers "F.Cu" "F.Mask" "F.Paste")
			(net "GND")
		)
		(zone
			(layer "F.Cu")
			(hatch none 0.5)
			(connect_pads
				(clearance 0)
			)
			(min_thickness 0.25)
			(keepout
				(tracks allowed)
				(vias not_allowed)
				(pads allowed)
				(copperpour not_allowed)
				(footprints allowed)
			)
			(placement
				(enabled no)
				(sheetname "")
			)
			(fill
				(thermal_gap 0.5)
				(thermal_bridge_width 0.5)
				(island_removal_mode 0)
			)
			(polygon
				(pts
					(xy 173.99 -64.38138) (xy 173.99 -64.88938) (xy 174.371 -64.88938) (xy 174.371 -64.38138)
				)
			)
		)
		(zone
			(layer "F.Cu")
			(hatch none 0.5)
			(connect_pads
				(clearance 0)
			)
			(min_thickness 0.25)
			(keepout
				(tracks not_allowed)
				(vias allowed)
				(pads allowed)
				(copperpour not_allowed)
				(footprints allowed)
			)
			(placement
				(enabled no)
				(sheetname "")
			)
			(fill
				(thermal_gap 0.5)
				(thermal_bridge_width 0.5)
				(island_removal_mode 0)
			)
			(polygon
				(pts
					(xy 174.371 -64.38138) (xy 174.371 -64.88938) (xy 173.99 -64.88938) (xy 173.99 -64.38138)
				)
			)
		)
	)
)
